(kicad_pcb
	(version 20241229)
	(generator "pcbnew")
	(generator_version "9.0")
	(general
		(thickness 1.6296)
		(legacy_teardrops no)
	)
	(paper "A3")
	(title_block
		(title "Thunderbolt to 10GbE adapter")
		(date "2026-04-21")
		(rev "1.1.0")
		(company "Antmicro Ltd")
		(comment 1 "www.antmicro.com")
		(comment 9 "footprints 291-294 of 703")
	)
	(layers
		(0 "F.Cu" signal)
		(4 "In1.Cu" signal)
		(6 "In2.Cu" signal)
		(8 "In3.Cu" signal)
		(10 "In4.Cu" signal)
		(12 "In5.Cu" signal)
		(14 "In6.Cu" signal)
		(2 "B.Cu" signal)
		(9 "F.Adhes" user "F.Adhesive")
		(11 "B.Adhes" user "B.Adhesive")
		(13 "F.Paste" user)
		(15 "B.Paste" user)
		(5 "F.SilkS" user "F.Silkscreen")
		(7 "B.SilkS" user "B.Silkscreen")
		(1 "F.Mask" user)
		(3 "B.Mask" user)
		(17 "Dwgs.User" user "User.Drawings")
		(19 "Cmts.User" user "User.Comments")
		(21 "Eco1.User" user "User.Eco1")
		(23 "Eco2.User" user "User.Eco2")
		(25 "Edge.Cuts" user)
		(27 "Margin" user)
		(31 "F.CrtYd" user "F.Courtyard")
		(29 "B.CrtYd" user "B.Courtyard")
		(35 "F.Fab" user)
		(33 "B.Fab" user)
	)
	(footprint "antmicro-footprints:C_0402_1005Metric"
		(layer "F.Cu")
		(at 133 130.2)
		(descr "Capacitor SMD 0402")
		(tags "capacitor SMD 0402")
		(property "Reference" "C86"
			(at -3.2 0.4 0)
			(layer "F.SilkS")
			(effects
				(font
					(size 0.7 0.7)
					(thickness 0.15)
				)
				(justify left bottom)
			)
		)
		(property "Value" "C_100n_0402"
			(at -1.022927 2.155213 0)
			(layer "F.Fab")
			(effects
				(font
					(size 0.7 0.7)
					(thickness 0.15)
				)
				(justify left bottom)
			)
		)
		(property "Datasheet" "https://www.murata.com/products/productdetail?partno=GRM155R61H104KE14%23"
			(at 0 0 0)
			(layer "F.Fab")
			(hide yes)
			(effects
				(font
					(size 1.27 1.27)
					(thickness 0.15)
				)
			)
		)
		(property "Description" "SMD Multilayer Ceramic Capacitor, 0.1 µF, 50 V, 0402 [1005 Metric], ± 10%, X5R, GRM Series"
			(at 0 0 0)
			(layer "F.Fab")
			(hide yes)
			(effects
				(font
					(size 1.27 1.27)
					(thickness 0.15)
				)
			)
		)
		(property "MPN" "GRM155R61H104KE14D"
			(at 0 0 0)
			(unlocked yes)
			(layer "F.Fab")
			(hide yes)
			(effects
				(font
					(size 1 1)
					(thickness 0.15)
				)
			)
		)
		(property "Manufacturer" "Murata"
			(at 0 0 0)
			(unlocked yes)
			(layer "F.Fab")
			(hide yes)
			(effects
				(font
					(size 1 1)
					(thickness 0.15)
				)
			)
		)
		(property "License" "Apache-2.0"
			(at 0 0 0)
			(unlocked yes)
			(layer "F.Fab")
			(hide yes)
			(effects
				(font
					(size 1 1)
					(thickness 0.15)
				)
			)
		)
		(property "Val" "100n"
			(at 0 0 0)
			(unlocked yes)
			(layer "F.Fab")
			(hide yes)
			(effects
				(font
					(size 1 1)
					(thickness 0.15)
				)
			)
		)
		(property "Voltage" "50V"
			(at 0 0 0)
			(unlocked yes)
			(layer "F.Fab")
			(hide yes)
			(effects
				(font
					(size 1 1)
					(thickness 0.15)
				)
			)
		)
		(property "Dielectric" "X5R"
			(at 0 0 0)
			(unlocked yes)
			(layer "F.Fab")
			(hide yes)
			(effects
				(font
					(size 1 1)
					(thickness 0.15)
				)
			)
		)
		(property "Author" "Antmicro"
			(at 0 0 0)
			(unlocked yes)
			(layer "F.Fab")
			(hide yes)
			(effects
				(font
					(size 1 1)
					(thickness 0.15)
				)
			)
		)
		(sheetname "/TB Controller - Power/")
		(sheetfile "tb-power.kicad_sch")
		(attr smd)
		(fp_rect
			(start -0.925 -0.47)
			(end 0.925 0.47)
			(stroke
				(width 0.05)
				(type default)
			)
			(fill no)
			(layer "F.CrtYd")
		)
		(fp_line
			(start -0.494 -0.25)
			(end 0.504 -0.25)
			(stroke
				(width 0.15)
				(type solid)
			)
			(layer "F.Fab")
		)
		(fp_line
			(start -0.494 0.248)
			(end -0.494 -0.25)
			(stroke
				(width 0.15)
				(type solid)
			)
			(layer "F.Fab")
		)
		(fp_line
			(start 0.504 -0.25)
			(end 0.504 0.248)
			(stroke
				(width 0.15)
				(type solid)
			)
			(layer "F.Fab")
		)
		(fp_line
			(start 0.504 0.248)
			(end -0.494 0.248)
			(stroke
				(width 0.15)
				(type solid)
			)
			(layer "F.Fab")
		)
		(fp_text user "Author: Antmicro"
			(at -0.939 3.399 0)
			(layer "F.Fab")
			(effects
				(font
					(size 0.7 0.7)
					(thickness 0.15)
				)
				(justify left bottom)
			)
		)
		(fp_text user "${REFERENCE}"
			(at -0.939 4.599 0)
			(layer "F.Fab")
			(effects
				(font
					(size 0.7 0.7)
					(thickness 0.15)
				)
				(justify left bottom)
			)
		)
		(fp_text user "License: Apache-2.0"
			(at -0.939 5.799 0)
			(layer "F.Fab")
			(effects
				(font
					(size 0.7 0.7)
					(thickness 0.15)
				)
				(justify left bottom)
			)
		)
		(pad "1" smd roundrect
			(at -0.48 0)
			(size 0.59 0.64)
			(layers "F.Cu" "F.Mask" "F.Paste")
			(roundrect_rratio 0.25)
			(net 23 "GND")
			(pintype "passive")
		)
		(pad "2" smd roundrect
			(at 0.48 0)
			(size 0.59 0.64)
			(layers "F.Cu" "F.Mask" "F.Paste")
			(roundrect_rratio 0.25)
			(net 57 "+3V3_TB")
			(pintype "passive")
		)
	)
	(footprint "antmicro-footprints:Vishay_PowerPAK_1212-8_Single"
		(layer "F.Cu")
		(at 136 62.8 180)
		(descr "PowerPAK 1212-8 Single")
		(tags "Vishay PowerPAK 1212-8 Single")
		(property "Reference" "Q8"
			(at 1.8 -2.8 180)
			(layer "F.SilkS")
			(effects
				(font
					(size 0.7 0.7)
					(thickness 0.15)
				)
				(justify left bottom)
			)
		)
		(property "Value" "SQS401EN-T1_BE3"
			(at 0 2.7 180)
			(layer "F.Fab")
			(effects
				(font
					(size 0.7 0.7)
					(thickness 0.15)
				)
				(justify left bottom)
			)
		)
		(property "Datasheet" "https://www.vishay.com/docs/65529/sqs401en.pdf"
			(at 0 0 180)
			(layer "F.Fab")
			(hide yes)
			(effects
				(font
					(size 1.27 1.27)
					(thickness 0.15)
				)
			)
		)
		(property "Description" "MOSFET, P Channel, 40 V, 16A, 0.047 ohm, PowerPAK 1212-8, Surface Mount"
			(at 0 0 180)
			(layer "F.Fab")
			(hide yes)
			(effects
				(font
					(size 1.27 1.27)
					(thickness 0.15)
				)
			)
		)
		(property "MPN" "SQS401EN-T1_BE3"
			(at 0 0 180)
			(unlocked yes)
			(layer "F.Fab")
			(hide yes)
			(effects
				(font
					(size 1 1)
					(thickness 0.15)
				)
			)
		)
		(property "Manufacturer" "Vishay"
			(at 0 0 180)
			(unlocked yes)
			(layer "F.Fab")
			(hide yes)
			(effects
				(font
					(size 1 1)
					(thickness 0.15)
				)
			)
		)
		(property "Author" "Antmicro"
			(at 0 0 180)
			(unlocked yes)
			(layer "F.Fab")
			(hide yes)
			(effects
				(font
					(size 1 1)
					(thickness 0.15)
				)
			)
		)
		(property "License" "Apache-2.0"
			(at 0 0 180)
			(unlocked yes)
			(layer "F.Fab")
			(hide yes)
			(effects
				(font
					(size 1 1)
					(thickness 0.15)
				)
			)
		)
		(sheetname "/Power input/")
		(sheetfile "power_input.kicad_sch")
		(attr smd)
		(fp_line
			(start 1.648 -1.651)
			(end 1.648 -1.317)
			(stroke
				(width 0.15)
				(type solid)
			)
			(layer "F.SilkS")
		)
		(fp_line
			(start 1.634 1.3)
			(end 1.634 1.634)
			(stroke
				(width 0.15)
				(type solid)
			)
			(layer "F.SilkS")
		)
		(fp_line
			(start -1.635 1.634)
			(end 1.634 1.634)
			(stroke
				(width 0.15)
				(type solid)
			)
			(layer "F.SilkS")
		)
		(fp_line
			(start -1.635 1.3)
			(end -1.635 1.634)
			(stroke
				(width 0.15)
				(type solid)
			)
			(layer "F.SilkS")
		)
		(fp_line
			(start -1.651 -1.651)
			(end 1.648 -1.651)
			(stroke
				(width 0.15)
				(type solid)
			)
			(layer "F.SilkS")
		)
		(fp_line
			(start -1.651 -1.651)
			(end -1.651 -1.317)
			(stroke
				(width 0.15)
				(type solid)
			)
			(layer "F.SilkS")
		)
		(fp_circle
			(center -1.9 -1.4)
			(end -1.85 -1.4)
			(stroke
				(width 0.15)
				(type solid)
			)
			(fill yes)
			(layer "F.SilkS")
		)
		(fp_rect
			(start -2 -1.8)
			(end 2 1.798)
			(stroke
				(width 0.05)
				(type solid)
			)
			(fill no)
			(layer "F.CrtYd")
		)
		(fp_line
			(start -1.6425 -1.4175)
			(end -1.4175 -1.6425)
			(stroke
				(width 0.15)
				(type solid)
			)
			(layer "F.Fab")
		)
		(fp_rect
			(start -1.651 -1.651)
			(end 1.648 1.648)
			(stroke
				(width 0.15)
				(type solid)
			)
			(fill no)
			(layer "F.Fab")
		)
		(fp_text user "Author: Antmicro"
			(at -8 5.9 180)
			(layer "F.Fab")
			(effects
				(font
					(size 0.7 0.7)
					(thickness 0.15)
				)
				(justify left bottom)
			)
		)
		(fp_text user "${REFERENCE}"
			(at -8 4.7 180)
			(layer "F.Fab")
			(effects
				(font
					(size 0.7 0.7)
					(thickness 0.15)
				)
				(justify left bottom)
			)
		)
		(fp_text user "License: Apache-2.0"
			(at -8 7.1 180)
			(layer "F.Fab")
			(effects
				(font
					(size 0.7 0.7)
					(thickness 0.15)
				)
				(justify left bottom)
			)
		)
		(pad "1" smd rect
			(at -1.436 -0.99 180)
			(size 0.99 0.405)
			(layers "F.Cu" "F.Mask" "F.Paste")
			(net 40 "+5V")
			(pinfunction "S")
			(pintype "passive")
		)
		(pad "2" smd rect
			(at -1.436 -0.332 180)
			(size 0.99 0.405)
			(layers "F.Cu" "F.Mask" "F.Paste")
			(net 40 "+5V")
			(pinfunction "S")
			(pintype "passive")
		)
		(pad "3" smd rect
			(at -1.436 0.33 180)
			(size 0.99 0.405)
			(layers "F.Cu" "F.Mask" "F.Paste")
			(net 40 "+5V")
			(pinfunction "S")
			(pintype "passive")
		)
		(pad "4" smd rect
			(at -1.436 0.988 180)
			(size 0.99 0.405)
			(layers "F.Cu" "F.Mask" "F.Paste")
			(net 433 "Net-(Q8-G)")
			(pinfunction "G")
			(pintype "passive")
		)
		(pad "5" smd custom
			(at 0.557 0 180)
			(size 1.725 2.235)
			(layers "F.Cu" "F.Mask" "F.Paste")
			(net 53 "+5V_USB")
			(pinfunction "D")
			(pintype "passive")
			(zone_connect 2)
			(options
				(clearance outline)
				(anchor rect)
			)
			(primitives
				(gr_poly
					(pts
						(xy 0.8625 0.1275) (xy 0.8625 -0.1275) (xy 1.3725 -0.1275) (xy 1.3725 -0.5325) (xy 0.8625 -0.5325)
						(xy 0.8625 -0.7875) (xy 1.3725 -0.7875) (xy 1.3725 -1.195) (xy 0.6125 -1.195) (xy 0.6125 1.195)
						(xy 1.3725 1.195) (xy 1.3725 0.7875) (xy 0.8625 0.7875) (xy 0.8625 0.5325) (xy 1.3725 0.5325)
						(xy 1.3725 0.1275)
					)
					(width 0)
					(fill yes)
				)
			)
		)
	)
	(footprint "antmicro-footprints:C_0603_1608Metric_EIA"
		(layer "F.Cu")
		(at 154.900002 113)
		(descr "Capacitor SMD 0603, IPC-7351 Density Level A")
		(tags "Capacitor 0603")
		(property "Reference" "C111"
			(at 13.650003 16.799998 0)
			(layer "F.SilkS")
			(effects
				(font
					(size 0.7 0.7)
					(thickness 0.15)
				)
			)
		)
		(property "Value" "C_22u_16V_0603"
			(at -1.42757 1.770288 0)
			(layer "F.Fab")
			(effects
				(font
					(size 0.7 0.7)
					(thickness 0.15)
				)
				(justify left bottom)
			)
		)
		(property "Datasheet" "https://product.samsungsem.com/mlcc/CL10A226MO7JZN.do"
			(at 0 0 0)
			(layer "F.Fab")
			(hide yes)
			(effects
				(font
					(size 1.27 1.27)
					(thickness 0.15)
				)
			)
		)
		(property "Description" "SMD Multilayer Ceramic Capacitor"
			(at 0 0 0)
			(layer "F.Fab")
			(hide yes)
			(effects
				(font
					(size 1.27 1.27)
					(thickness 0.15)
				)
			)
		)
		(property "MPN" "CL10A226MO7JZNC"
			(at 0 0 0)
			(unlocked yes)
			(layer "F.Fab")
			(hide yes)
			(effects
				(font
					(size 1 1)
					(thickness 0.15)
				)
			)
		)
		(property "Manufacturer" "Samsung Electro-Mechanics"
			(at 0 0 0)
			(unlocked yes)
			(layer "F.Fab")
			(hide yes)
			(effects
				(font
					(size 1 1)
					(thickness 0.15)
				)
			)
		)
		(property "License" "Apache-2.0"
			(at 0 0 0)
			(unlocked yes)
			(layer "F.Fab")
			(hide yes)
			(effects
				(font
					(size 1 1)
					(thickness 0.15)
				)
			)
		)
		(property "Author" "Antmicro"
			(at 0 0 0)
			(unlocked yes)
			(layer "F.Fab")
			(hide yes)
			(effects
				(font
					(size 1 1)
					(thickness 0.15)
				)
			)
		)
		(property "Val" "22u"
			(at 0 0 0)
			(unlocked yes)
			(layer "F.Fab")
			(hide yes)
			(effects
				(font
					(size 1 1)
					(thickness 0.15)
				)
			)
		)
		(property "Voltage" "16V"
			(at 0 0 0)
			(unlocked yes)
			(layer "F.Fab")
			(hide yes)
			(effects
				(font
					(size 1 1)
					(thickness 0.15)
				)
			)
		)
		(property "Dielectric" ""
			(at 0 0 0)
			(unlocked yes)
			(layer "F.Fab")
			(hide yes)
			(effects
				(font
					(size 1 1)
					(thickness 0.15)
				)
			)
		)
		(sheetname "/X710 DCDC converters/")
		(sheetfile "DCDC_converters_X710.kicad_sch")
		(attr smd)
		(fp_line
			(start -0.15 -0.55)
			(end 0.15 -0.55)
			(stroke
				(width 0.15)
				(type solid)
			)
			(layer "F.SilkS")
		)
		(fp_line
			(start -0.15 0.55)
			(end 0.15 0.55)
			(stroke
				(width 0.15)
				(type solid)
			)
			(layer "F.SilkS")
		)
		(fp_rect
			(start -1.25 -0.65)
			(end 1.25 0.65)
			(stroke
				(width 0.05)
				(type solid)
			)
			(fill no)
			(layer "F.CrtYd")
		)
		(fp_rect
			(start -0.8 -0.45)
			(end 0.8 0.45)
			(stroke
				(width 0.15)
				(type solid)
			)
			(fill no)
			(layer "F.Fab")
		)
		(fp_text user "Author: Antmicro"
			(at -1.682 4.894 0)
			(layer "F.Fab")
			(effects
				(font
					(size 0.7 0.7)
					(thickness 0.15)
				)
				(justify left bottom)
			)
		)
		(fp_text user "License: Apache-2.0"
			(at -1.682 5.895 0)
			(layer "F.Fab")
			(effects
				(font
					(size 0.7 0.7)
					(thickness 0.15)
				)
				(justify left bottom)
			)
		)
		(fp_text user "${REFERENCE}"
			(at -1.682 3.895 0)
			(layer "F.Fab")
			(effects
				(font
					(size 0.7 0.7)
					(thickness 0.15)
				)
				(justify left bottom)
			)
		)
		(pad "1" smd roundrect
			(at -0.7 0)
			(size 0.8 1.1)
			(layers "F.Cu" "F.Mask" "F.Paste")
			(roundrect_rratio 0.2)
			(net 23 "GND")
			(pintype "passive")
		)
		(pad "2" smd roundrect
			(at 0.7 0)
			(size 0.8 1.1)
			(layers "F.Cu" "F.Mask" "F.Paste")
			(roundrect_rratio 0.2)
			(net 40 "+5V")
			(pintype "passive")
		)
	)
	(footprint "antmicro-footprints:R_0402_1005Metric"
		(layer "F.Cu")
		(at 139.5 145.5 180)
		(descr "Resistor SMD 0402")
		(tags "resistor SMD 0402")
		(property "Reference" "R74"
			(at 0.1 3.7 180)
			(layer "F.SilkS")
			(effects
				(font
					(size 0.7 0.7)
					(thickness 0.15)
				)
				(justify left bottom)
			)
		)
		(property "Value" "R_330R_0402"
			(at -1.011843 1.772047 180)
			(layer "F.Fab")
			(effects
				(font
					(size 0.7 0.7)
					(thickness 0.15)
				)
				(justify left bottom)
			)
		)
		(property "Datasheet" "https://www.bourns.com/docs/product-datasheets/cr.pdf"
			(at 0 0 180)
			(layer "F.Fab")
			(hide yes)
			(effects
				(font
					(size 1.27 1.27)
					(thickness 0.15)
				)
			)
		)
		(property "Description" "SMD Chip Resistor, 330 ohm, ± 1%, 62.5 mW, 0402 [1005 Metric], Thick Film, General Purpose"
			(at 0 0 180)
			(layer "F.Fab")
			(hide yes)
			(effects
				(font
					(size 1.27 1.27)
					(thickness 0.15)
				)
			)
		)
		(property "MPN" "CR0402-FX-3300GLF"
			(at 0 0 180)
			(unlocked yes)
			(layer "F.Fab")
			(hide yes)
			(effects
				(font
					(size 1 1)
					(thickness 0.15)
				)
			)
		)
		(property "Manufacturer" "Bourns"
			(at 0 0 180)
			(unlocked yes)
			(layer "F.Fab")
			(hide yes)
			(effects
				(font
					(size 1 1)
					(thickness 0.15)
				)
			)
		)
		(property "License" "Apache-2.0"
			(at 0 0 180)
			(unlocked yes)
			(layer "F.Fab")
			(hide yes)
			(effects
				(font
					(size 1 1)
					(thickness 0.15)
				)
			)
		)
		(property "Val" "330R"
			(at 0 0 180)
			(unlocked yes)
			(layer "F.Fab")
			(hide yes)
			(effects
				(font
					(size 1 1)
					(thickness 0.15)
				)
			)
		)
		(property "Tolerance" "1%"
			(at 0 0 180)
			(unlocked yes)
			(layer "F.Fab")
			(hide yes)
			(effects
				(font
					(size 1 1)
					(thickness 0.15)
				)
			)
		)
		(property "Author" "Antmicro"
			(at 0 0 180)
			(unlocked yes)
			(layer "F.Fab")
			(hide yes)
			(effects
				(font
					(size 1 1)
					(thickness 0.15)
				)
			)
		)
		(sheetname "/TB Controller - Power/")
		(sheetfile "tb-power.kicad_sch")
		(attr smd)
		(fp_rect
			(start -0.925 -0.47)
			(end 0.925 0.47)
			(stroke
				(width 0.05)
				(type default)
			)
			(fill no)
			(layer "F.CrtYd")
		)
		(fp_rect
			(start -0.5 -0.25)
			(end 0.5 0.25)
			(stroke
				(width 0.15)
				(type solid)
			)
			(fill no)
			(layer "F.Fab")
		)
		(fp_text user "Author: Antmicro"
			(at -0.95 4.169 180)
			(layer "F.Fab")
			(effects
				(font
					(size 0.7 0.7)
					(thickness 0.15)
				)
				(justify left bottom)
			)
		)
		(fp_text user "${REFERENCE}"
			(at -0.95 3.168 180)
			(layer "F.Fab")
			(effects
				(font
					(size 0.7 0.7)
					(thickness 0.15)
				)
				(justify left bottom)
			)
		)
		(fp_text user "License: Apache-2.0"
			(at -0.95 5.169 180)
			(layer "F.Fab")
			(effects
				(font
					(size 0.7 0.7)
					(thickness 0.15)
				)
				(justify left bottom)
			)
		)
		(pad "1" smd roundrect
			(at -0.48 0 180)
			(size 0.59 0.64)
			(layers "F.Cu" "F.Mask" "F.Paste")
			(roundrect_rratio 0.25)
			(net 197 "Net-(Q1-C)")
			(pintype "passive")
		)
		(pad "2" smd roundrect
			(at 0.48 0 180)
			(size 0.59 0.64)
			(layers "F.Cu" "F.Mask" "F.Paste")
			(roundrect_rratio 0.25)
			(net 19 "Net-(D5-C)")
			(pintype "passive")
		)
	)
)
